(kicad_pcb
	(version 20260206)
	(generator "pcbnew")
	(generator_version "10.0")
	(general
		(thickness 1.6)
		(legacy_teardrops no)
	)
	(paper "A4")
	(title_block
		(title "panther-plus-userver — 13130-1b_20150205.brd")
		(comment 1 "Honey Badger (Wiwynn) / footprint 1214 of 1509 (DIMM3), pads 114-120 of 210")
	)
	(layers
		(0 "F.Cu" signal "TOP")
		(4 "In1.Cu" signal "L2")
		(6 "In2.Cu" signal "L3")
		(8 "In3.Cu" signal "L4")
		(10 "In4.Cu" signal "L5")
		(12 "In5.Cu" signal "L6")
		(14 "In6.Cu" signal "L7")
		(16 "In7.Cu" signal "L8")
		(18 "In8.Cu" signal "L9")
		(20 "In9.Cu" signal "L10")
		(22 "In10.Cu" signal "L11")
		(2 "B.Cu" signal "BOTTOM")
		(9 "F.Adhes" user "F.Adhesive")
		(11 "B.Adhes" user "B.Adhesive")
		(13 "F.Paste" user "Package Geometry/Pastemask Top")
		(15 "B.Paste" user "Package Geometry/Pastemask Bottom")
		(5 "F.SilkS" user "Ref Des/Silkscreen Top")
		(7 "B.SilkS" user "Ref Des/Silkscreen Bottom")
		(1 "F.Mask" user "Board Geometry/Soldermask Top")
		(3 "B.Mask" user "Board Geometry/Soldermask Bottom")
		(17 "Dwgs.User" user "User.Drawings")
		(19 "Cmts.User" user "User.Comments")
		(21 "Eco1.User" user "User.Eco1")
		(23 "Eco2.User" user "User.Eco2")
		(25 "Edge.Cuts" user "Board Geometry/Outline")
		(27 "Margin" user)
		(31 "F.CrtYd" user "Package Geometry/Place Bound Top")
		(29 "B.CrtYd" user "Package Geometry/Place Bound Bottom")
		(35 "F.Fab" user "Ref Des/Assembly Top")
		(33 "B.Fab" user "Ref Des/Assembly Bottom")
	)
	(footprint ""
		(layer "B.Cu")
		(at 159.999934 -5.790692)
		(property "Reference" "DIMM3"
			(at 0 0 0)
			(layer "B.SilkS")
			(hide yes)
			(effects
				(font
					(size 1.27 1.27)
				)
				(justify mirror)
			)
		)
		(property "Value" "DDR3-204P-142-COLAY-1-GP-U"
			(at 41.312338 -16.676878 0)
			(unlocked yes)
			(layer "B.Fab")
			(hide yes)
			(effects
				(font
					(size 1.016 1.016)
					(thickness 0.1524)
				)
				(justify mirror)
			)
		)
		(property "Device Type" "AS0A626-J8R6-7H-COLAY-1"
			(at 41.312338 -18.200878 0)
			(unlocked yes)
			(layer "B.Fab")
			(hide yes)
			(effects
				(font
					(size 1.016 1.016)
					(thickness 0.1524)
				)
				(justify mirror)
			)
		)
		(duplicate_pad_numbers_are_jumpers no)
		(pad "112" smd custom
			(at 4.05003 4.100068 180)
			(size 0.1143 0.1143)
			(layers "B.Cu" "B.Mask" "B.Paste")
			(net "M_B_CK_DP1")
			(options
				(clearance outline)
				(anchor circle)
			)
			(primitives
				(gr_poly
					(pts
						(xy 0 -0.9017) (xy -0.03175 -0.89916) (xy -0.0635 -0.889) (xy -0.09144 -0.87376) (xy -0.11684 -0.85344)
						(xy -0.13716 -0.82804) (xy -0.1524 -0.8001) (xy -0.16256 -0.76835) (xy -0.1651 -0.7366) (xy -0.1651 -0.11938)
						(xy -0.17272 -0.11176) (xy -0.19812 -0.0762) (xy -0.2032 -0.06604) (xy -0.20701 -0.05715) (xy -0.21209 -0.04699)
						(xy -0.2159 -0.03683) (xy -0.21844 -0.02667) (xy -0.22225 -0.01524) (xy -0.22352 -0.00508) (xy -0.22606 0.00508)
						(xy -0.22733 0.01651) (xy -0.22733 0.02667) (xy -0.2286 0.0381) (xy -0.22733 0.04953) (xy -0.22733 0.05969)
						(xy -0.22606 0.07112) (xy -0.22352 0.08128) (xy -0.22225 0.09144) (xy -0.21844 0.10287) (xy -0.2159 0.11303)
						(xy -0.21209 0.12319) (xy -0.20701 0.13335) (xy -0.2032 0.14224) (xy -0.19812 0.1524) (xy -0.17272 0.18796)
						(xy -0.1651 0.19558) (xy -0.1651 0.7366) (xy -0.16256 0.76835) (xy -0.1524 0.8001) (xy -0.13716 0.82804)
						(xy -0.11684 0.85344) (xy -0.09144 0.87376) (xy -0.0635 0.889) (xy -0.03175 0.89916) (xy 0 0.9017)
						(xy 0.03175 0.89916) (xy 0.0635 0.889) (xy 0.09144 0.87376) (xy 0.11684 0.85344) (xy 0.13716 0.82804)
						(xy 0.1524 0.8001) (xy 0.16256 0.76835) (xy 0.1651 0.7366) (xy 0.1651 0.19685) (xy 0.17272 0.18923)
						(xy 0.17907 0.18034) (xy 0.18669 0.17145) (xy 0.19177 0.16256) (xy 0.19812 0.15367) (xy 0.20828 0.13335)
						(xy 0.21971 0.10287) (xy 0.22225 0.09271) (xy 0.22479 0.08128) (xy 0.22606 0.07112) (xy 0.2286 0.05969)
						(xy 0.2286 0.01651) (xy 0.22606 0.00508) (xy 0.22479 -0.00508) (xy 0.22225 -0.01651) (xy 0.21971 -0.02667)
						(xy 0.20828 -0.05715) (xy 0.19812 -0.07747) (xy 0.19177 -0.08636) (xy 0.18669 -0.09525) (xy 0.17907 -0.10414)
						(xy 0.17272 -0.11303) (xy 0.1651 -0.12065) (xy 0.1651 -0.7366) (xy 0.16256 -0.76835) (xy 0.1524 -0.8001)
						(xy 0.13716 -0.82804) (xy 0.11684 -0.85344) (xy 0.09144 -0.87376) (xy 0.0635 -0.889) (xy 0.03175 -0.89916)
					)
					(width 0)
					(fill yes)
				)
			)
		)
		(pad "113" smd custom
			(at 4.350004 -4.100068 180)
			(size 0.1143 0.1143)
			(layers "B.Cu" "B.Mask" "B.Paste")
			(net "M_B_CK_DN0")
			(options
				(clearance outline)
				(anchor circle)
			)
			(primitives
				(gr_poly
					(pts
						(xy 0 -0.9017) (xy -0.03175 -0.89916) (xy -0.0635 -0.889) (xy -0.09144 -0.87376) (xy -0.11684 -0.85344)
						(xy -0.13716 -0.82804) (xy -0.1524 -0.8001) (xy -0.16256 -0.76835) (xy -0.1651 -0.7366) (xy -0.1651 -0.44958)
						(xy -0.17272 -0.44196) (xy -0.19812 -0.4064) (xy -0.2032 -0.39624) (xy -0.20701 -0.38735) (xy -0.21209 -0.37719)
						(xy -0.2159 -0.36703) (xy -0.21844 -0.35687) (xy -0.22225 -0.34544) (xy -0.22352 -0.33528) (xy -0.22606 -0.32512)
						(xy -0.22733 -0.31369) (xy -0.22733 -0.30353) (xy -0.2286 -0.2921) (xy -0.22733 -0.28067) (xy -0.22733 -0.27051)
						(xy -0.22606 -0.25908) (xy -0.22352 -0.24892) (xy -0.22225 -0.23876) (xy -0.21844 -0.22733) (xy -0.2159 -0.21717)
						(xy -0.21209 -0.20701) (xy -0.20701 -0.19685) (xy -0.2032 -0.18796) (xy -0.19812 -0.1778) (xy -0.17272 -0.14224)
						(xy -0.1651 -0.13462) (xy -0.1651 0.7366) (xy -0.16256 0.76835) (xy -0.1524 0.8001) (xy -0.13716 0.82804)
						(xy -0.11684 0.85344) (xy -0.09144 0.87376) (xy -0.0635 0.889) (xy -0.03175 0.89916) (xy 0 0.9017)
						(xy 0.03175 0.89916) (xy 0.0635 0.889) (xy 0.09144 0.87376) (xy 0.11684 0.85344) (xy 0.13716 0.82804)
						(xy 0.1524 0.8001) (xy 0.16256 0.76835) (xy 0.1651 0.7366) (xy 0.1651 -0.13462) (xy 0.17272 -0.14224)
						(xy 0.19812 -0.1778) (xy 0.2032 -0.18796) (xy 0.20701 -0.19685) (xy 0.21209 -0.20701) (xy 0.2159 -0.21717)
						(xy 0.21844 -0.22733) (xy 0.22225 -0.23876) (xy 0.22352 -0.24892) (xy 0.22606 -0.25908) (xy 0.22733 -0.27051)
						(xy 0.22733 -0.28067) (xy 0.2286 -0.2921) (xy 0.22733 -0.30353) (xy 0.22733 -0.31369) (xy 0.22606 -0.32512)
						(xy 0.22352 -0.33528) (xy 0.22225 -0.34544) (xy 0.21844 -0.35687) (xy 0.2159 -0.36703) (xy 0.21209 -0.37719)
						(xy 0.20701 -0.38735) (xy 0.2032 -0.39624) (xy 0.19812 -0.4064) (xy 0.17272 -0.44196) (xy 0.1651 -0.44958)
						(xy 0.1651 -0.7366) (xy 0.16256 -0.76835) (xy 0.1524 -0.8001) (xy 0.13716 -0.82804) (xy 0.11684 -0.85344)
						(xy 0.09144 -0.87376) (xy 0.0635 -0.889) (xy 0.03175 -0.89916)
					)
					(width 0)
					(fill yes)
				)
			)
		)
		(pad "114" smd custom
			(at 4.649978 4.100068 180)
			(size 0.1143 0.1143)
			(layers "B.Cu" "B.Mask" "B.Paste")
			(net "M_B_CK_DN1")
			(options
				(clearance outline)
				(anchor circle)
			)
			(primitives
				(gr_poly
					(pts
						(xy 0 -0.9017) (xy -0.03175 -0.89916) (xy -0.0635 -0.889) (xy -0.09144 -0.87376) (xy -0.11684 -0.85344)
						(xy -0.13716 -0.82804) (xy -0.1524 -0.8001) (xy -0.16256 -0.76835) (xy -0.1651 -0.7366) (xy -0.1651 0.13462)
						(xy -0.17272 0.14224) (xy -0.19812 0.1778) (xy -0.2032 0.18796) (xy -0.20701 0.19685) (xy -0.21209 0.20701)
						(xy -0.2159 0.21717) (xy -0.21844 0.22733) (xy -0.22225 0.23876) (xy -0.22352 0.24892) (xy -0.22606 0.25908)
						(xy -0.22733 0.27051) (xy -0.22733 0.28067) (xy -0.2286 0.2921) (xy -0.22733 0.30353) (xy -0.22733 0.31369)
						(xy -0.22606 0.32512) (xy -0.22352 0.33528) (xy -0.22225 0.34544) (xy -0.21844 0.35687) (xy -0.2159 0.36703)
						(xy -0.21209 0.37719) (xy -0.20701 0.38735) (xy -0.2032 0.39624) (xy -0.19812 0.4064) (xy -0.17272 0.44196)
						(xy -0.1651 0.44958) (xy -0.1651 0.7366) (xy -0.16256 0.76835) (xy -0.1524 0.8001) (xy -0.13716 0.82804)
						(xy -0.11684 0.85344) (xy -0.09144 0.87376) (xy -0.0635 0.889) (xy -0.03175 0.89916) (xy 0 0.9017)
						(xy 0.03175 0.89916) (xy 0.0635 0.889) (xy 0.09144 0.87376) (xy 0.11684 0.85344) (xy 0.13716 0.82804)
						(xy 0.1524 0.8001) (xy 0.16256 0.76835) (xy 0.1651 0.7366) (xy 0.1651 0.44958) (xy 0.17272 0.44196)
						(xy 0.19812 0.4064) (xy 0.2032 0.39624) (xy 0.20701 0.38735) (xy 0.21209 0.37719) (xy 0.2159 0.36703)
						(xy 0.21844 0.35687) (xy 0.22225 0.34544) (xy 0.22352 0.33528) (xy 0.22606 0.32512) (xy 0.22733 0.31369)
						(xy 0.22733 0.30353) (xy 0.2286 0.2921) (xy 0.22733 0.28067) (xy 0.22733 0.27051) (xy 0.22606 0.25908)
						(xy 0.22352 0.24892) (xy 0.22225 0.23876) (xy 0.21844 0.22733) (xy 0.2159 0.21717) (xy 0.21209 0.20701)
						(xy 0.20701 0.19685) (xy 0.2032 0.18796) (xy 0.19812 0.1778) (xy 0.17272 0.14224) (xy 0.1651 0.13462)
						(xy 0.1651 -0.7366) (xy 0.16256 -0.76835) (xy 0.1524 -0.8001) (xy 0.13716 -0.82804) (xy 0.11684 -0.85344)
						(xy 0.09144 -0.87376) (xy 0.0635 -0.889) (xy 0.03175 -0.89916)
					)
					(width 0)
					(fill yes)
				)
			)
		)
		(pad "115" smd custom
			(at 4.949952 -4.100068 180)
			(size 0.1143 0.1143)
			(layers "B.Cu" "B.Mask" "B.Paste")
			(net "PV_VDDR")
			(options
				(clearance outline)
				(anchor circle)
			)
			(primitives
				(gr_poly
					(pts
						(xy 0 -0.9017) (xy -0.03175 -0.89916) (xy -0.0635 -0.889) (xy -0.09144 -0.87376) (xy -0.11684 -0.85344)
						(xy -0.13716 -0.82804) (xy -0.1524 -0.8001) (xy -0.16256 -0.76835) (xy -0.1651 -0.7366) (xy -0.1651 -0.19685)
						(xy -0.17272 -0.18923) (xy -0.17907 -0.18034) (xy -0.18669 -0.17145) (xy -0.19177 -0.16256) (xy -0.19812 -0.15367)
						(xy -0.20828 -0.13335) (xy -0.21971 -0.10287) (xy -0.22225 -0.09271) (xy -0.22479 -0.08128) (xy -0.22606 -0.07112)
						(xy -0.2286 -0.05969) (xy -0.2286 -0.01651) (xy -0.22606 -0.00508) (xy -0.22479 0.00508) (xy -0.22225 0.01651)
						(xy -0.21971 0.02667) (xy -0.20828 0.05715) (xy -0.19812 0.07747) (xy -0.19177 0.08636) (xy -0.18669 0.09525)
						(xy -0.17907 0.10414) (xy -0.17272 0.11303) (xy -0.1651 0.12065) (xy -0.1651 0.7366) (xy -0.16256 0.76835)
						(xy -0.1524 0.8001) (xy -0.13716 0.82804) (xy -0.11684 0.85344) (xy -0.09144 0.87376) (xy -0.0635 0.889)
						(xy -0.03175 0.89916) (xy 0 0.9017) (xy 0.03175 0.89916) (xy 0.0635 0.889) (xy 0.09144 0.87376)
						(xy 0.11684 0.85344) (xy 0.13716 0.82804) (xy 0.1524 0.8001) (xy 0.16256 0.76835) (xy 0.1651 0.7366)
						(xy 0.1651 0.11938) (xy 0.17272 0.11176) (xy 0.19812 0.0762) (xy 0.2032 0.06604) (xy 0.20701 0.05715)
						(xy 0.21209 0.04699) (xy 0.2159 0.03683) (xy 0.21844 0.02667) (xy 0.22225 0.01524) (xy 0.22352 0.00508)
						(xy 0.22606 -0.00508) (xy 0.22733 -0.01651) (xy 0.22733 -0.02667) (xy 0.2286 -0.0381) (xy 0.22733 -0.04953)
						(xy 0.22733 -0.05969) (xy 0.22606 -0.07112) (xy 0.22352 -0.08128) (xy 0.22225 -0.09144) (xy 0.21844 -0.10287)
						(xy 0.2159 -0.11303) (xy 0.21209 -0.12319) (xy 0.20701 -0.13335) (xy 0.2032 -0.14224) (xy 0.19812 -0.1524)
						(xy 0.17272 -0.18796) (xy 0.1651 -0.19558) (xy 0.1651 -0.7366) (xy 0.16256 -0.76835) (xy 0.1524 -0.8001)
						(xy 0.13716 -0.82804) (xy 0.11684 -0.85344) (xy 0.09144 -0.87376) (xy 0.0635 -0.889) (xy 0.03175 -0.89916)
					)
					(width 0)
					(fill yes)
				)
			)
		)
		(pad "116" smd custom
			(at 5.249926 4.100068 180)
			(size 0.1143 0.1143)
			(layers "B.Cu" "B.Mask" "B.Paste")
			(net "PV_VDDR")
			(options
				(clearance outline)
				(anchor circle)
			)
			(primitives
				(gr_poly
					(pts
						(xy 0 -0.9017) (xy -0.03175 -0.89916) (xy -0.0635 -0.889) (xy -0.09144 -0.87376) (xy -0.11684 -0.85344)
						(xy -0.13716 -0.82804) (xy -0.1524 -0.8001) (xy -0.16256 -0.76835) (xy -0.1651 -0.7366) (xy -0.1651 -0.11938)
						(xy -0.17272 -0.11176) (xy -0.19812 -0.0762) (xy -0.2032 -0.06604) (xy -0.20701 -0.05715) (xy -0.21209 -0.04699)
						(xy -0.2159 -0.03683) (xy -0.21844 -0.02667) (xy -0.22225 -0.01524) (xy -0.22352 -0.00508) (xy -0.22606 0.00508)
						(xy -0.22733 0.01651) (xy -0.22733 0.02667) (xy -0.2286 0.0381) (xy -0.22733 0.04953) (xy -0.22733 0.05969)
						(xy -0.22606 0.07112) (xy -0.22352 0.08128) (xy -0.22225 0.09144) (xy -0.21844 0.10287) (xy -0.2159 0.11303)
						(xy -0.21209 0.12319) (xy -0.20701 0.13335) (xy -0.2032 0.14224) (xy -0.19812 0.1524) (xy -0.17272 0.18796)
						(xy -0.1651 0.19558) (xy -0.1651 0.7366) (xy -0.16256 0.76835) (xy -0.1524 0.8001) (xy -0.13716 0.82804)
						(xy -0.11684 0.85344) (xy -0.09144 0.87376) (xy -0.0635 0.889) (xy -0.03175 0.89916) (xy 0 0.9017)
						(xy 0.03175 0.89916) (xy 0.0635 0.889) (xy 0.09144 0.87376) (xy 0.11684 0.85344) (xy 0.13716 0.82804)
						(xy 0.1524 0.8001) (xy 0.16256 0.76835) (xy 0.1651 0.7366) (xy 0.1651 0.19685) (xy 0.17272 0.18923)
						(xy 0.17907 0.18034) (xy 0.18669 0.17145) (xy 0.19177 0.16256) (xy 0.19812 0.15367) (xy 0.20828 0.13335)
						(xy 0.21971 0.10287) (xy 0.22225 0.09271) (xy 0.22479 0.08128) (xy 0.22606 0.07112) (xy 0.2286 0.05969)
						(xy 0.2286 0.01651) (xy 0.22606 0.00508) (xy 0.22479 -0.00508) (xy 0.22225 -0.01651) (xy 0.21971 -0.02667)
						(xy 0.20828 -0.05715) (xy 0.19812 -0.07747) (xy 0.19177 -0.08636) (xy 0.18669 -0.09525) (xy 0.17907 -0.10414)
						(xy 0.17272 -0.11303) (xy 0.1651 -0.12065) (xy 0.1651 -0.7366) (xy 0.16256 -0.76835) (xy 0.1524 -0.8001)
						(xy 0.13716 -0.82804) (xy 0.11684 -0.85344) (xy 0.09144 -0.87376) (xy 0.0635 -0.889) (xy 0.03175 -0.89916)
					)
					(width 0)
					(fill yes)
				)
			)
		)
		(pad "117" smd custom
			(at 5.5499 -4.100068 180)
			(size 0.1143 0.1143)
			(layers "B.Cu" "B.Mask" "B.Paste")
			(net "M_B_MA10")
			(options
				(clearance outline)
				(anchor circle)
			)
			(primitives
				(gr_poly
					(pts
						(xy 0 -0.9017) (xy -0.03175 -0.89916) (xy -0.0635 -0.889) (xy -0.09144 -0.87376) (xy -0.11684 -0.85344)
						(xy -0.13716 -0.82804) (xy -0.1524 -0.8001) (xy -0.16256 -0.76835) (xy -0.1651 -0.7366) (xy -0.1651 -0.44958)
						(xy -0.17272 -0.44196) (xy -0.19812 -0.4064) (xy -0.2032 -0.39624) (xy -0.20701 -0.38735) (xy -0.21209 -0.37719)
						(xy -0.2159 -0.36703) (xy -0.21844 -0.35687) (xy -0.22225 -0.34544) (xy -0.22352 -0.33528) (xy -0.22606 -0.32512)
						(xy -0.22733 -0.31369) (xy -0.22733 -0.30353) (xy -0.2286 -0.2921) (xy -0.22733 -0.28067) (xy -0.22733 -0.27051)
						(xy -0.22606 -0.25908) (xy -0.22352 -0.24892) (xy -0.22225 -0.23876) (xy -0.21844 -0.22733) (xy -0.2159 -0.21717)
						(xy -0.21209 -0.20701) (xy -0.20701 -0.19685) (xy -0.2032 -0.18796) (xy -0.19812 -0.1778) (xy -0.17272 -0.14224)
						(xy -0.1651 -0.13462) (xy -0.1651 0.7366) (xy -0.16256 0.76835) (xy -0.1524 0.8001) (xy -0.13716 0.82804)
						(xy -0.11684 0.85344) (xy -0.09144 0.87376) (xy -0.0635 0.889) (xy -0.03175 0.89916) (xy 0 0.9017)
						(xy 0.03175 0.89916) (xy 0.0635 0.889) (xy 0.09144 0.87376) (xy 0.11684 0.85344) (xy 0.13716 0.82804)
						(xy 0.1524 0.8001) (xy 0.16256 0.76835) (xy 0.1651 0.7366) (xy 0.1651 -0.13462) (xy 0.17272 -0.14224)
						(xy 0.19812 -0.1778) (xy 0.2032 -0.18796) (xy 0.20701 -0.19685) (xy 0.21209 -0.20701) (xy 0.2159 -0.21717)
						(xy 0.21844 -0.22733) (xy 0.22225 -0.23876) (xy 0.22352 -0.24892) (xy 0.22606 -0.25908) (xy 0.22733 -0.27051)
						(xy 0.22733 -0.28067) (xy 0.2286 -0.2921) (xy 0.22733 -0.30353) (xy 0.22733 -0.31369) (xy 0.22606 -0.32512)
						(xy 0.22352 -0.33528) (xy 0.22225 -0.34544) (xy 0.21844 -0.35687) (xy 0.2159 -0.36703) (xy 0.21209 -0.37719)
						(xy 0.20701 -0.38735) (xy 0.2032 -0.39624) (xy 0.19812 -0.4064) (xy 0.17272 -0.44196) (xy 0.1651 -0.44958)
						(xy 0.1651 -0.7366) (xy 0.16256 -0.76835) (xy 0.1524 -0.8001) (xy 0.13716 -0.82804) (xy 0.11684 -0.85344)
						(xy 0.09144 -0.87376) (xy 0.0635 -0.889) (xy 0.03175 -0.89916)
					)
					(width 0)
					(fill yes)
				)
			)
		)
		(pad "118" smd custom
			(at 5.849874 4.100068 180)
			(size 0.1143 0.1143)
			(layers "B.Cu" "B.Mask" "B.Paste")
			(net "Net_8")
			(options
				(clearance outline)
				(anchor circle)
			)
			(primitives
				(gr_poly
					(pts
						(xy 0 -0.9017) (xy -0.03175 -0.89916) (xy -0.0635 -0.889) (xy -0.09144 -0.87376) (xy -0.11684 -0.85344)
						(xy -0.13716 -0.82804) (xy -0.1524 -0.8001) (xy -0.16256 -0.76835) (xy -0.1651 -0.7366) (xy -0.1651 0.13462)
						(xy -0.17272 0.14224) (xy -0.19812 0.1778) (xy -0.2032 0.18796) (xy -0.20701 0.19685) (xy -0.21209 0.20701)
						(xy -0.2159 0.21717) (xy -0.21844 0.22733) (xy -0.22225 0.23876) (xy -0.22352 0.24892) (xy -0.22606 0.25908)
						(xy -0.22733 0.27051) (xy -0.22733 0.28067) (xy -0.2286 0.2921) (xy -0.22733 0.30353) (xy -0.22733 0.31369)
						(xy -0.22606 0.32512) (xy -0.22352 0.33528) (xy -0.22225 0.34544) (xy -0.21844 0.35687) (xy -0.2159 0.36703)
						(xy -0.21209 0.37719) (xy -0.20701 0.38735) (xy -0.2032 0.39624) (xy -0.19812 0.4064) (xy -0.17272 0.44196)
						(xy -0.1651 0.44958) (xy -0.1651 0.7366) (xy -0.16256 0.76835) (xy -0.1524 0.8001) (xy -0.13716 0.82804)
						(xy -0.11684 0.85344) (xy -0.09144 0.87376) (xy -0.0635 0.889) (xy -0.03175 0.89916) (xy 0 0.9017)
						(xy 0.03175 0.89916) (xy 0.0635 0.889) (xy 0.09144 0.87376) (xy 0.11684 0.85344) (xy 0.13716 0.82804)
						(xy 0.1524 0.8001) (xy 0.16256 0.76835) (xy 0.1651 0.7366) (xy 0.1651 0.44958) (xy 0.17272 0.44196)
						(xy 0.19812 0.4064) (xy 0.2032 0.39624) (xy 0.20701 0.38735) (xy 0.21209 0.37719) (xy 0.2159 0.36703)
						(xy 0.21844 0.35687) (xy 0.22225 0.34544) (xy 0.22352 0.33528) (xy 0.22606 0.32512) (xy 0.22733 0.31369)
						(xy 0.22733 0.30353) (xy 0.2286 0.2921) (xy 0.22733 0.28067) (xy 0.22733 0.27051) (xy 0.22606 0.25908)
						(xy 0.22352 0.24892) (xy 0.22225 0.23876) (xy 0.21844 0.22733) (xy 0.2159 0.21717) (xy 0.21209 0.20701)
						(xy 0.20701 0.19685) (xy 0.2032 0.18796) (xy 0.19812 0.1778) (xy 0.17272 0.14224) (xy 0.1651 0.13462)
						(xy 0.1651 -0.7366) (xy 0.16256 -0.76835) (xy 0.1524 -0.8001) (xy 0.13716 -0.82804) (xy 0.11684 -0.85344)
						(xy 0.09144 -0.87376) (xy 0.0635 -0.889) (xy 0.03175 -0.89916)
					)
					(width 0)
					(fill yes)
				)
			)
		)
	)
)
